(kicad_pcb
	(version 20260206)
	(generator "pcbnew")
	(generator_version "10.0")
	(general
		(thickness 1.6)
		(legacy_teardrops no)
	)
	(paper "A4")
	(title_block
		(title "03242023_DA0F0TMBIJ0_F0T_Motherboard_J_brd_V01_OCP.brd")
		(comment 1 "Grand Teton / footprints 637-642 of 6105")
	)
	(layers
		(0 "F.Cu" signal "TOP")
		(4 "In1.Cu" signal "GND")
		(6 "In2.Cu" signal "IN1")
		(8 "In3.Cu" signal "GND1")
		(10 "In4.Cu" signal "IN2")
		(12 "In5.Cu" signal "GND2")
		(14 "In6.Cu" signal "IN3")
		(16 "In7.Cu" signal "GND3")
		(18 "In8.Cu" signal "VCC")
		(20 "In9.Cu" signal "VCC1")
		(22 "In10.Cu" signal "GND4")
		(24 "In11.Cu" signal "IN4")
		(26 "In12.Cu" signal "GND5")
		(28 "In13.Cu" signal "IN5")
		(30 "In14.Cu" signal "GND6")
		(32 "In15.Cu" signal "IN6")
		(34 "In16.Cu" signal "GND7")
		(2 "B.Cu" signal "BOTTOM")
		(9 "F.Adhes" user "F.Adhesive")
		(11 "B.Adhes" user "B.Adhesive")
		(13 "F.Paste" user "Package Geometry/Pastemask Top")
		(15 "B.Paste" user "Package Geometry/Pastemask Bottom")
		(5 "F.SilkS" user "Ref Des/Silkscreen Top")
		(7 "B.SilkS" user "Ref Des/Silkscreen Bottom")
		(1 "F.Mask" user "Board Geometry/Soldermask Top")
		(3 "B.Mask" user "Board Geometry/Soldermask Bottom")
		(17 "Dwgs.User" user "User.Drawings")
		(19 "Cmts.User" user "User.Comments")
		(21 "Eco1.User" user "User.Eco1")
		(23 "Eco2.User" user "User.Eco2")
		(25 "Edge.Cuts" user "Board Geometry/Outline")
		(27 "Margin" user)
		(31 "F.CrtYd" user "Package Geometry/Place Bound Top")
		(29 "B.CrtYd" user "Package Geometry/Place Bound Bottom")
		(35 "F.Fab" user "Ref Des/Assembly Top")
		(33 "B.Fab" user "Ref Des/Assembly Bottom")
	)
	(footprint ""
		(layer "F.Cu")
		(at 183.85028 -411.20568 -90)
		(property "Reference" "R4793"
			(at 0 0 270)
			(layer "F.SilkS")
			(hide yes)
			(effects
				(font
					(size 1.27 1.27)
				)
			)
		)
		(property "Value" ""
			(at 0 0 270)
			(layer "F.Fab")
			(effects
				(font
					(size 1.27 1.27)
				)
			)
		)
		(duplicate_pad_numbers_are_jumpers no)
		(fp_line
			(start -0.7874 0.4064)
			(end -0.7874 -0.4064)
			(stroke
				(width 0.1524)
				(type default)
			)
			(layer "F.SilkS")
		)
		(fp_line
			(start 0.7874 0.4064)
			(end -0.7874 0.4064)
			(stroke
				(width 0.1524)
				(type default)
			)
			(layer "F.SilkS")
		)
		(fp_line
			(start -0.7874 -0.4064)
			(end 0.7874 -0.4064)
			(stroke
				(width 0.1524)
				(type default)
			)
			(layer "F.SilkS")
		)
		(fp_line
			(start 0.7874 -0.4064)
			(end 0.7874 0.4064)
			(stroke
				(width 0.1524)
				(type default)
			)
			(layer "F.SilkS")
		)
		(fp_line
			(start -0.67945 0.3048)
			(end -0.67945 -0.305054)
			(stroke
				(width 0.1)
				(type default)
			)
			(layer "F.Fab")
		)
		(fp_line
			(start -0.12065 0.3048)
			(end -0.67945 0.3048)
			(stroke
				(width 0.1)
				(type default)
			)
			(layer "F.Fab")
		)
		(fp_line
			(start 0.120396 0.3048)
			(end 0.120396 0.2794)
			(stroke
				(width 0.1)
				(type default)
			)
			(layer "F.Fab")
		)
		(fp_line
			(start 0.67945 0.3048)
			(end 0.120396 0.3048)
			(stroke
				(width 0.1)
				(type default)
			)
			(layer "F.Fab")
		)
		(fp_line
			(start -0.12065 0.2794)
			(end -0.12065 0.3048)
			(stroke
				(width 0.1)
				(type default)
			)
			(layer "F.Fab")
		)
		(fp_line
			(start 0.120396 0.2794)
			(end -0.12065 0.2794)
			(stroke
				(width 0.1)
				(type default)
			)
			(layer "F.Fab")
		)
		(fp_line
			(start -0.12065 -0.2794)
			(end 0.12065 -0.2794)
			(stroke
				(width 0.1)
				(type default)
			)
			(layer "F.Fab")
		)
		(fp_line
			(start 0.12065 -0.2794)
			(end 0.12065 -0.3048)
			(stroke
				(width 0.1)
				(type default)
			)
			(layer "F.Fab")
		)
		(fp_line
			(start 0.12065 -0.3048)
			(end 0.67945 -0.3048)
			(stroke
				(width 0.1)
				(type default)
			)
			(layer "F.Fab")
		)
		(fp_line
			(start 0.67945 -0.3048)
			(end 0.67945 0.3048)
			(stroke
				(width 0.1)
				(type default)
			)
			(layer "F.Fab")
		)
		(fp_line
			(start -0.67945 -0.305054)
			(end -0.12065 -0.305054)
			(stroke
				(width 0.1)
				(type default)
			)
			(layer "F.Fab")
		)
		(fp_line
			(start -0.12065 -0.305054)
			(end -0.12065 -0.2794)
			(stroke
				(width 0.1)
				(type default)
			)
			(layer "F.Fab")
		)
		(pad "1" smd circle
			(at -0.40005 0 270)
			(size 0 0)
			(layers "F.Cu" "F.Mask" "F.Paste")
			(net "HSC_OC_VOL")
		)
		(pad "2" smd circle
			(at 0.40005 0 270)
			(size 0 0)
			(layers "F.Cu" "F.Mask" "F.Paste")
			(net "HSC_D_OC_R2")
		)
	)
	(footprint ""
		(layer "F.Cu")
		(at 114.013742 -338.180172 90)
		(property "Reference" "PR1789"
			(at 0 0 90)
			(layer "F.SilkS")
			(hide yes)
			(effects
				(font
					(size 1.27 1.27)
				)
			)
		)
		(property "Value" ""
			(at 0 0 90)
			(layer "F.Fab")
			(effects
				(font
					(size 1.27 1.27)
				)
			)
		)
		(duplicate_pad_numbers_are_jumpers no)
		(fp_line
			(start 0.7874 -0.4064)
			(end 0.7874 0.4064)
			(stroke
				(width 0.1524)
				(type default)
			)
			(layer "F.SilkS")
		)
		(fp_line
			(start -0.7874 -0.4064)
			(end 0.7874 -0.4064)
			(stroke
				(width 0.1524)
				(type default)
			)
			(layer "F.SilkS")
		)
		(fp_line
			(start 0.7874 0.4064)
			(end -0.7874 0.4064)
			(stroke
				(width 0.1524)
				(type default)
			)
			(layer "F.SilkS")
		)
		(fp_line
			(start -0.7874 0.4064)
			(end -0.7874 -0.4064)
			(stroke
				(width 0.1524)
				(type default)
			)
			(layer "F.SilkS")
		)
		(fp_line
			(start -0.12065 -0.305054)
			(end -0.12065 -0.2794)
			(stroke
				(width 0.1)
				(type default)
			)
			(layer "F.Fab")
		)
		(fp_line
			(start -0.67945 -0.305054)
			(end -0.12065 -0.305054)
			(stroke
				(width 0.1)
				(type default)
			)
			(layer "F.Fab")
		)
		(fp_line
			(start 0.67945 -0.3048)
			(end 0.67945 0.3048)
			(stroke
				(width 0.1)
				(type default)
			)
			(layer "F.Fab")
		)
		(fp_line
			(start 0.12065 -0.3048)
			(end 0.67945 -0.3048)
			(stroke
				(width 0.1)
				(type default)
			)
			(layer "F.Fab")
		)
		(fp_line
			(start 0.12065 -0.2794)
			(end 0.12065 -0.3048)
			(stroke
				(width 0.1)
				(type default)
			)
			(layer "F.Fab")
		)
		(fp_line
			(start -0.12065 -0.2794)
			(end 0.12065 -0.2794)
			(stroke
				(width 0.1)
				(type default)
			)
			(layer "F.Fab")
		)
		(fp_line
			(start 0.120396 0.2794)
			(end -0.12065 0.2794)
			(stroke
				(width 0.1)
				(type default)
			)
			(layer "F.Fab")
		)
		(fp_line
			(start -0.12065 0.2794)
			(end -0.12065 0.3048)
			(stroke
				(width 0.1)
				(type default)
			)
			(layer "F.Fab")
		)
		(fp_line
			(start 0.67945 0.3048)
			(end 0.120396 0.3048)
			(stroke
				(width 0.1)
				(type default)
			)
			(layer "F.Fab")
		)
		(fp_line
			(start 0.120396 0.3048)
			(end 0.120396 0.2794)
			(stroke
				(width 0.1)
				(type default)
			)
			(layer "F.Fab")
		)
		(fp_line
			(start -0.12065 0.3048)
			(end -0.67945 0.3048)
			(stroke
				(width 0.1)
				(type default)
			)
			(layer "F.Fab")
		)
		(fp_line
			(start -0.67945 0.3048)
			(end -0.67945 -0.305054)
			(stroke
				(width 0.1)
				(type default)
			)
			(layer "F.Fab")
		)
		(pad "1" smd circle
			(at -0.40005 0 90)
			(size 0 0)
			(layers "F.Cu" "F.Mask" "F.Paste")
			(net "SW_PVCCIN_CPU1_BOOT3")
		)
		(pad "2" smd circle
			(at 0.40005 0 90)
			(size 0 0)
			(layers "F.Cu" "F.Mask" "F.Paste")
			(net "SW_PVCCIN_CPU1_BOOT3_R")
		)
	)
	(footprint ""
		(layer "F.Cu")
		(at 109.337856 -32.64281)
		(property "Reference" "R3243"
			(at 0 0 0)
			(layer "F.SilkS")
			(hide yes)
			(effects
				(font
					(size 1.27 1.27)
				)
			)
		)
		(property "Value" ""
			(at 0 0 0)
			(layer "F.Fab")
			(effects
				(font
					(size 1.27 1.27)
				)
			)
		)
		(duplicate_pad_numbers_are_jumpers no)
		(fp_line
			(start -0.7874 -0.4064)
			(end 0.7874 -0.4064)
			(stroke
				(width 0.1524)
				(type default)
			)
			(layer "F.SilkS")
		)
		(fp_line
			(start -0.7874 0.4064)
			(end -0.7874 -0.4064)
			(stroke
				(width 0.1524)
				(type default)
			)
			(layer "F.SilkS")
		)
		(fp_line
			(start 0.7874 -0.4064)
			(end 0.7874 0.4064)
			(stroke
				(width 0.1524)
				(type default)
			)
			(layer "F.SilkS")
		)
		(fp_line
			(start 0.7874 0.4064)
			(end -0.7874 0.4064)
			(stroke
				(width 0.1524)
				(type default)
			)
			(layer "F.SilkS")
		)
		(fp_line
			(start -0.67945 -0.305054)
			(end -0.12065 -0.305054)
			(stroke
				(width 0.1)
				(type default)
			)
			(layer "F.Fab")
		)
		(fp_line
			(start -0.67945 0.3048)
			(end -0.67945 -0.305054)
			(stroke
				(width 0.1)
				(type default)
			)
			(layer "F.Fab")
		)
		(fp_line
			(start -0.12065 -0.305054)
			(end -0.12065 -0.2794)
			(stroke
				(width 0.1)
				(type default)
			)
			(layer "F.Fab")
		)
		(fp_line
			(start -0.12065 -0.2794)
			(end 0.12065 -0.2794)
			(stroke
				(width 0.1)
				(type default)
			)
			(layer "F.Fab")
		)
		(fp_line
			(start -0.12065 0.2794)
			(end -0.12065 0.3048)
			(stroke
				(width 0.1)
				(type default)
			)
			(layer "F.Fab")
		)
		(fp_line
			(start -0.12065 0.3048)
			(end -0.67945 0.3048)
			(stroke
				(width 0.1)
				(type default)
			)
			(layer "F.Fab")
		)
		(fp_line
			(start 0.120396 0.2794)
			(end -0.12065 0.2794)
			(stroke
				(width 0.1)
				(type default)
			)
			(layer "F.Fab")
		)
		(fp_line
			(start 0.120396 0.3048)
			(end 0.120396 0.2794)
			(stroke
				(width 0.1)
				(type default)
			)
			(layer "F.Fab")
		)
		(fp_line
			(start 0.12065 -0.3048)
			(end 0.67945 -0.3048)
			(stroke
				(width 0.1)
				(type default)
			)
			(layer "F.Fab")
		)
		(fp_line
			(start 0.12065 -0.2794)
			(end 0.12065 -0.3048)
			(stroke
				(width 0.1)
				(type default)
			)
			(layer "F.Fab")
		)
		(fp_line
			(start 0.67945 -0.3048)
			(end 0.67945 0.3048)
			(stroke
				(width 0.1)
				(type default)
			)
			(layer "F.Fab")
		)
		(fp_line
			(start 0.67945 0.3048)
			(end 0.120396 0.3048)
			(stroke
				(width 0.1)
				(type default)
			)
			(layer "F.Fab")
		)
		(pad "1" smd circle
			(at -0.40005 0)
			(size 0 0)
			(layers "F.Cu" "F.Mask" "F.Paste")
			(net "SMB_OCP_V3_2_3V3AUX_SDA")
		)
		(pad "2" smd circle
			(at 0.40005 0)
			(size 0 0)
			(layers "F.Cu" "F.Mask" "F.Paste")
			(net "P3V3_AUX")
		)
	)
	(footprint ""
		(layer "F.Cu")
		(at 385.91109 -408.517344 -90)
		(property "Reference" "C879"
			(at 0 0 270)
			(layer "F.SilkS")
			(hide yes)
			(effects
				(font
					(size 1.27 1.27)
				)
			)
		)
		(property "Value" ""
			(at 0 0 270)
			(layer "F.Fab")
			(effects
				(font
					(size 1.27 1.27)
				)
			)
		)
		(duplicate_pad_numbers_are_jumpers no)
		(fp_line
			(start -0.299974 0.150114)
			(end -0.299974 -0.150114)
			(stroke
				(width 0.1)
				(type default)
			)
			(layer "F.Fab")
		)
		(fp_line
			(start 0.299974 0.150114)
			(end -0.299974 0.150114)
			(stroke
				(width 0.1)
				(type default)
			)
			(layer "F.Fab")
		)
		(fp_line
			(start -0.299974 -0.150114)
			(end 0.299974 -0.150114)
			(stroke
				(width 0.1)
				(type default)
			)
			(layer "F.Fab")
		)
		(fp_line
			(start 0.299974 -0.150114)
			(end 0.299974 0.150114)
			(stroke
				(width 0.1)
				(type default)
			)
			(layer "F.Fab")
		)
		(pad "1" smd rect
			(at -0.2667 0 270)
			(size 0.3048 0.381)
			(layers "F.Cu" "F.Mask" "F.Paste")
			(net "P5E_CPU0_PE3_TX_C_DP<11>")
		)
		(pad "2" smd rect
			(at 0.2667 0 270)
			(size 0.3048 0.381)
			(layers "F.Cu" "F.Mask" "F.Paste")
			(net "P5E_CPU0_PE3_TX_DP<11>")
		)
	)
	(footprint ""
		(layer "F.Cu")
		(at 262.84809 -75.61834 90)
		(property "Reference" "PC2000"
			(at 0 0 90)
			(layer "F.SilkS")
			(hide yes)
			(effects
				(font
					(size 1.27 1.27)
				)
			)
		)
		(property "Value" ""
			(at 0 0 90)
			(layer "F.Fab")
			(effects
				(font
					(size 1.27 1.27)
				)
			)
		)
		(duplicate_pad_numbers_are_jumpers no)
		(fp_line
			(start 0.7874 -0.4064)
			(end 0.7874 0.4064)
			(stroke
				(width 0.1524)
				(type default)
			)
			(layer "F.SilkS")
		)
		(fp_line
			(start -0.7874 -0.4064)
			(end 0.7874 -0.4064)
			(stroke
				(width 0.1524)
				(type default)
			)
			(layer "F.SilkS")
		)
		(fp_line
			(start 0.7874 0.4064)
			(end -0.7874 0.4064)
			(stroke
				(width 0.1524)
				(type default)
			)
			(layer "F.SilkS")
		)
		(fp_line
			(start -0.7874 0.4064)
			(end -0.7874 -0.4064)
			(stroke
				(width 0.1524)
				(type default)
			)
			(layer "F.SilkS")
		)
		(fp_line
			(start -0.12065 -0.305054)
			(end -0.12065 -0.2794)
			(stroke
				(width 0.1)
				(type default)
			)
			(layer "F.Fab")
		)
		(fp_line
			(start -0.67945 -0.305054)
			(end -0.12065 -0.305054)
			(stroke
				(width 0.1)
				(type default)
			)
			(layer "F.Fab")
		)
		(fp_line
			(start 0.67945 -0.3048)
			(end 0.67945 0.3048)
			(stroke
				(width 0.1)
				(type default)
			)
			(layer "F.Fab")
		)
		(fp_line
			(start 0.12065 -0.3048)
			(end 0.67945 -0.3048)
			(stroke
				(width 0.1)
				(type default)
			)
			(layer "F.Fab")
		)
		(fp_line
			(start 0.12065 -0.2794)
			(end 0.12065 -0.3048)
			(stroke
				(width 0.1)
				(type default)
			)
			(layer "F.Fab")
		)
		(fp_line
			(start -0.12065 -0.2794)
			(end 0.12065 -0.2794)
			(stroke
				(width 0.1)
				(type default)
			)
			(layer "F.Fab")
		)
		(fp_line
			(start 0.120396 0.2794)
			(end -0.12065 0.2794)
			(stroke
				(width 0.1)
				(type default)
			)
			(layer "F.Fab")
		)
		(fp_line
			(start -0.12065 0.2794)
			(end -0.12065 0.3048)
			(stroke
				(width 0.1)
				(type default)
			)
			(layer "F.Fab")
		)
		(fp_line
			(start 0.67945 0.3048)
			(end 0.120396 0.3048)
			(stroke
				(width 0.1)
				(type default)
			)
			(layer "F.Fab")
		)
		(fp_line
			(start 0.120396 0.3048)
			(end 0.120396 0.2794)
			(stroke
				(width 0.1)
				(type default)
			)
			(layer "F.Fab")
		)
		(fp_line
			(start -0.12065 0.3048)
			(end -0.67945 0.3048)
			(stroke
				(width 0.1)
				(type default)
			)
			(layer "F.Fab")
		)
		(fp_line
			(start -0.67945 0.3048)
			(end -0.67945 -0.305054)
			(stroke
				(width 0.1)
				(type default)
			)
			(layer "F.Fab")
		)
		(pad "1" smd circle
			(at -0.40005 0 90)
			(size 0 0)
			(layers "F.Cu" "F.Mask" "F.Paste")
			(net "P1V05_PCH_AUX_REF")
		)
		(pad "2" smd circle
			(at 0.40005 0 90)
			(size 0 0)
			(layers "F.Cu" "F.Mask" "F.Paste")
			(net "GND")
		)
	)
	(footprint ""
		(layer "F.Cu")
		(at 38.02888 -434.939948)
		(property "Reference" "R3523"
			(at 0 0 0)
			(layer "F.SilkS")
			(hide yes)
			(effects
				(font
					(size 1.27 1.27)
				)
			)
		)
		(property "Value" ""
			(at 0 0 0)
			(layer "F.Fab")
			(effects
				(font
					(size 1.27 1.27)
				)
			)
		)
		(duplicate_pad_numbers_are_jumpers no)
		(fp_line
			(start -0.7874 -0.4064)
			(end 0.7874 -0.4064)
			(stroke
				(width 0.1524)
				(type default)
			)
			(layer "F.SilkS")
		)
		(fp_line
			(start -0.7874 0.4064)
			(end -0.7874 -0.4064)
			(stroke
				(width 0.1524)
				(type default)
			)
			(layer "F.SilkS")
		)
		(fp_line
			(start 0.7874 -0.4064)
			(end 0.7874 0.4064)
			(stroke
				(width 0.1524)
				(type default)
			)
			(layer "F.SilkS")
		)
		(fp_line
			(start 0.7874 0.4064)
			(end -0.7874 0.4064)
			(stroke
				(width 0.1524)
				(type default)
			)
			(layer "F.SilkS")
		)
		(fp_line
			(start -0.67945 -0.305054)
			(end -0.12065 -0.305054)
			(stroke
				(width 0.1)
				(type default)
			)
			(layer "F.Fab")
		)
		(fp_line
			(start -0.67945 0.3048)
			(end -0.67945 -0.305054)
			(stroke
				(width 0.1)
				(type default)
			)
			(layer "F.Fab")
		)
		(fp_line
			(start -0.12065 -0.305054)
			(end -0.12065 -0.2794)
			(stroke
				(width 0.1)
				(type default)
			)
			(layer "F.Fab")
		)
		(fp_line
			(start -0.12065 -0.2794)
			(end 0.12065 -0.2794)
			(stroke
				(width 0.1)
				(type default)
			)
			(layer "F.Fab")
		)
		(fp_line
			(start -0.12065 0.2794)
			(end -0.12065 0.3048)
			(stroke
				(width 0.1)
				(type default)
			)
			(layer "F.Fab")
		)
		(fp_line
			(start -0.12065 0.3048)
			(end -0.67945 0.3048)
			(stroke
				(width 0.1)
				(type default)
			)
			(layer "F.Fab")
		)
		(fp_line
			(start 0.120396 0.2794)
			(end -0.12065 0.2794)
			(stroke
				(width 0.1)
				(type default)
			)
			(layer "F.Fab")
		)
		(fp_line
			(start 0.120396 0.3048)
			(end 0.120396 0.2794)
			(stroke
				(width 0.1)
				(type default)
			)
			(layer "F.Fab")
		)
		(fp_line
			(start 0.12065 -0.3048)
			(end 0.67945 -0.3048)
			(stroke
				(width 0.1)
				(type default)
			)
			(layer "F.Fab")
		)
		(fp_line
			(start 0.12065 -0.2794)
			(end 0.12065 -0.3048)
			(stroke
				(width 0.1)
				(type default)
			)
			(layer "F.Fab")
		)
		(fp_line
			(start 0.67945 -0.3048)
			(end 0.67945 0.3048)
			(stroke
				(width 0.1)
				(type default)
			)
			(layer "F.Fab")
		)
		(fp_line
			(start 0.67945 0.3048)
			(end 0.120396 0.3048)
			(stroke
				(width 0.1)
				(type default)
			)
			(layer "F.Fab")
		)
		(pad "1" smd circle
			(at -0.40005 0)
			(size 0 0)
			(layers "F.Cu" "F.Mask" "F.Paste")
			(net "P3V3_AUX")
		)
		(pad "2" smd circle
			(at 0.40005 0)
			(size 0 0)
			(layers "F.Cu" "F.Mask" "F.Paste")
			(net "SMB_1_BMC_GPU_BUF_R_SCL")
		)
	)
)
